G04 ================== begin FILE IDENTIFICATION RECORD ==================*
G04 Layout Name:  F:/<user>/2022/FB/R4006-TIMING/brd/gerber-3/R4006-B0001-02_R01.brd*
G04 Film Name:    R4006-B0001-02_R01_BD_1-7*
G04 File Format:  Gerber RS274X*
G04 File Origin:  Cadence Allegro 17.2-S079*
G04 Origin Date:  Fri Feb 25 18:14:44 2022*
G04 *
G04 Layer:  BOARD GEOMETRY/OUTLINE*
G04 Layer:  MANUFACTURING/NCBACKDRILL-1-7*
G04 *
G04 Offset:    (0.00 0.00)*
G04 Mirror:    No*
G04 Mode:      Positive*
G04 Rotation:  0*
G04 FullContactRelief:  No*
G04 UndefLineWidth:     6.00*
G04 ================== end FILE IDENTIFICATION RECORD ====================*
%FSLAX55Y55*MOIN*%
%IR0*IPPOS*OFA0.00000B0.00000*MIA0B0*SFA1.00000B1.00000*%
%AMMACRO10*
1,1,.006,0.0,.025*
20,1,.006,0.0,.025,.004341,.02462,0.0*
1,1,.006,.004341,.02462*
20,1,.006,.004341,.02462,.008551,.023492,0.0*
1,1,.006,.008551,.023492*
20,1,.006,.008551,.023492,.0125,.021651,0.0*
1,1,.006,.0125,.021651*
20,1,.006,.0125,.021651,.01607,.019151,0.0*
1,1,.006,.01607,.019151*
20,1,.006,.01607,.019151,.019151,.01607,0.0*
1,1,.006,.019151,.01607*
20,1,.006,.019151,.01607,.021651,.0125,0.0*
1,1,.006,.021651,.0125*
20,1,.006,.021651,.0125,.023492,.008551,0.0*
1,1,.006,.023492,.008551*
20,1,.006,.023492,.008551,.02462,.004341,0.0*
1,1,.006,.02462,.004341*
20,1,.006,.02462,.004341,.025,0.0,0.0*
1,1,.006,.025,0.0*
20,1,.006,.025,0.0,.02462,-.004341,0.0*
1,1,.006,.02462,-.004341*
20,1,.006,.02462,-.004341,.023492,-.008551,0.0*
1,1,.006,.023492,-.008551*
20,1,.006,.023492,-.008551,.021651,-.0125,0.0*
1,1,.006,.021651,-.0125*
20,1,.006,.021651,-.0125,.019151,-.01607,0.0*
1,1,.006,.019151,-.01607*
20,1,.006,.019151,-.01607,.01607,-.019151,0.0*
1,1,.006,.01607,-.019151*
20,1,.006,.01607,-.019151,.0125,-.021651,0.0*
1,1,.006,.0125,-.021651*
20,1,.006,.0125,-.021651,.008551,-.023492,0.0*
1,1,.006,.008551,-.023492*
20,1,.006,.008551,-.023492,.004341,-.02462,0.0*
1,1,.006,.004341,-.02462*
20,1,.006,.004341,-.02462,0.0,-.025,0.0*
1,1,.006,0.0,-.025*
20,1,.006,0.0,-.025,-.004341,-.02462,0.0*
1,1,.006,-.004341,-.02462*
20,1,.006,-.004341,-.02462,-.008551,-.023492,0.0*
1,1,.006,-.008551,-.023492*
20,1,.006,-.008551,-.023492,-.0125,-.021651,0.0*
1,1,.006,-.0125,-.021651*
20,1,.006,-.0125,-.021651,-.01607,-.019151,0.0*
1,1,.006,-.01607,-.019151*
20,1,.006,-.01607,-.019151,-.019151,-.01607,0.0*
1,1,.006,-.019151,-.01607*
20,1,.006,-.019151,-.01607,-.021651,-.0125,0.0*
1,1,.006,-.021651,-.0125*
20,1,.006,-.021651,-.0125,-.023492,-.008551,0.0*
1,1,.006,-.023492,-.008551*
20,1,.006,-.023492,-.008551,-.02462,-.004341,0.0*
1,1,.006,-.02462,-.004341*
20,1,.006,-.02462,-.004341,-.025,0.0,0.0*
1,1,.006,-.025,0.0*
20,1,.006,-.025,0.0,-.02462,.004341,0.0*
1,1,.006,-.02462,.004341*
20,1,.006,-.02462,.004341,-.023492,.008551,0.0*
1,1,.006,-.023492,.008551*
20,1,.006,-.023492,.008551,-.021651,.0125,0.0*
1,1,.006,-.021651,.0125*
20,1,.006,-.021651,.0125,-.019151,.01607,0.0*
1,1,.006,-.019151,.01607*
20,1,.006,-.019151,.01607,-.01607,.019151,0.0*
1,1,.006,-.01607,.019151*
20,1,.006,-.01607,.019151,-.0125,.021651,0.0*
1,1,.006,-.0125,.021651*
20,1,.006,-.0125,.021651,-.008551,.023492,0.0*
1,1,.006,-.008551,.023492*
20,1,.006,-.008551,.023492,-.004341,.02462,0.0*
1,1,.006,-.004341,.02462*
20,1,.006,-.004341,.02462,0.0,.025,0.0*
1,1,.006,0.0,.025*
1,1,.006,-.01042,-.0125*
20,1,.006,-.01042,-.0125,0.0,.0125,0.0*
1,1,.006,0.0,.0125*
20,1,.006,0.0,.0125,.01042,-.0125,0.0*
1,1,.006,.01042,-.0125*
1,1,.006,.00667,-.00375*
20,1,.006,.00667,-.00375,-.00667,-.00375,0.0*
1,1,.006,-.00667,-.00375*
%
%ADD10MACRO10*%
%ADD11C,.006*%
G75*
%LPD*%
G75*
G54D10*
X240508Y73100D03*
Y69900D03*
X247022Y76300D03*
X250222D03*
X269907D03*
X266707D03*
X285055D03*
X281855D03*
X314763Y85237D03*
X312500Y87500D03*
X938070Y-540337D03*
G54D11*
G01X658071Y284646D02*
G03X660039Y286614I0J1968D01*
G01Y433661D01*
G03X656102Y437598I-3937J0D01*
G01X3937D01*
G03X0Y433661I0J-3937D01*
G01Y21654D01*
G03X3937Y17717I3937J0D01*
G01X55118D01*
G03X59055Y21654I0J3937D01*
G01Y46260D01*
G02X62992Y50197I3937J0D01*
G01X127362D01*
G02X131299Y46260I0J-3937D01*
G01Y21654D01*
G03X135236Y17717I3937J0D01*
G01X158858D01*
G03X162795Y21654I0J3937D01*
G01Y43012D01*
G02X177165I7185J0D01*
G01Y1969D01*
X179134Y0D01*
X219291D01*
X221260Y1969D01*
Y29331D01*
G02X228740I3740J0D01*
G01Y1969D01*
X230709Y0D01*
X310236D01*
X312205Y1969D01*
Y46260D01*
G02X316142Y50197I3937J0D01*
G01X656102D01*
G03X660039Y54134I0J3937D01*
G01Y237500D01*
G03X658071Y239469I-1969J1D01*
G01X657211D01*
G02X655243Y241437I0J1968D01*
G01Y282677D01*
G02X657211Y284646I1968J0D01*
G01X658071D01*
G01X895755Y-661170D02*
X899785D01*
G01X918540Y-665337D02*
Y-652837D01*
X922570Y-663254D01*
X926600Y-652837D01*
Y-665337D01*
G01X932025D02*
Y-652837D01*
X937915D01*
G01X935745Y-658879D02*
X932025D01*
G01X948300Y-659087D02*
X951400D01*
Y-662837D01*
X950470Y-664087D01*
X949385Y-664920D01*
X947835Y-665337D01*
X946285Y-664920D01*
X945200Y-664087D01*
X944270Y-662837D01*
X943650Y-661379D01*
X943340Y-659712D01*
Y-658254D01*
X943650Y-657004D01*
X944270Y-655545D01*
X945200Y-654295D01*
X946130Y-653462D01*
X947370Y-652837D01*
X948455D01*
X949695Y-653254D01*
X950625Y-654087D01*
G01X955120Y-669504D02*
X964420D01*
G01X968915Y-663671D02*
X970155Y-664712D01*
X971550Y-665337D01*
X972790D01*
X974030Y-664712D01*
X974960Y-663671D01*
X975425Y-662212D01*
X975115Y-660754D01*
X974340Y-659504D01*
X972945Y-658670D01*
X971085Y-658254D01*
X970000Y-657420D01*
X969535Y-655962D01*
X969845Y-654504D01*
X970620Y-653462D01*
X971705Y-652837D01*
X972790D01*
X973875Y-653254D01*
X974805Y-654295D01*
G01X984570Y-652837D02*
Y-665337D01*
G01X981005Y-652837D02*
X988135D01*
G01X993560D02*
Y-661795D01*
X994180Y-663671D01*
X995420Y-664920D01*
X996970Y-665337D01*
X998520Y-664920D01*
X999760Y-663671D01*
X1000380Y-661795D01*
Y-652837D01*
G01X1010610Y-658670D02*
X1011230Y-658045D01*
X1011695Y-657004D01*
X1012005Y-655545D01*
X1011695Y-654295D01*
X1011075Y-653462D01*
X1009990Y-652837D01*
X1005805D01*
Y-665337D01*
X1010920D01*
X1012005Y-664504D01*
X1012625Y-663254D01*
X1012935Y-661795D01*
X1012625Y-660337D01*
X1011695Y-659087D01*
X1010610Y-658670D01*
X1005805D01*
G01X1034170Y-665754D02*
X1033860Y-665545D01*
Y-665129D01*
X1034170Y-664920D01*
X1034480Y-665129D01*
Y-665545D01*
X1034170Y-665754D01*
G01Y-660129D02*
X1033860Y-659920D01*
Y-659504D01*
X1034170Y-659295D01*
X1034480Y-659504D01*
Y-659920D01*
X1034170Y-660129D01*
G01X1054940Y-665337D02*
Y-652837D01*
X1058970Y-663254D01*
X1063000Y-652837D01*
Y-665337D01*
G01X1067495D02*
X1071370Y-652837D01*
X1075245Y-665337D01*
G01X1073850Y-660962D02*
X1068890D01*
G01X1080205Y-665337D02*
Y-652837D01*
X1087335Y-665337D01*
Y-652837D01*
G01X1092760D02*
Y-661795D01*
X1093380Y-663671D01*
X1094620Y-664920D01*
X1096170Y-665337D01*
X1097720Y-664920D01*
X1098960Y-663671D01*
X1099580Y-661795D01*
Y-652837D01*
G01X1105625Y-665337D02*
Y-652837D01*
X1111515D01*
G01X1109345Y-658879D02*
X1105625D01*
G01X1117095Y-665337D02*
X1120970Y-652837D01*
X1124845Y-665337D01*
G01X1123450Y-660962D02*
X1118490D01*
G01X1136780Y-653879D02*
X1135850Y-653254D01*
X1134765Y-652837D01*
X1133525D01*
X1132130Y-653462D01*
X1131045Y-654504D01*
X1130270Y-655754D01*
X1129650Y-657837D01*
X1129495Y-659712D01*
X1129805Y-661587D01*
X1130270Y-662837D01*
X1131200Y-664087D01*
X1132285Y-664920D01*
X1133370Y-665337D01*
X1134455D01*
X1135540Y-664920D01*
X1136470Y-664296D01*
X1137245Y-663462D01*
G01X1145770Y-652837D02*
Y-665337D01*
G01X1142205Y-652837D02*
X1149335D01*
G01X1154760D02*
Y-661795D01*
X1155380Y-663671D01*
X1156620Y-664920D01*
X1158170Y-665337D01*
X1159720Y-664920D01*
X1160960Y-663671D01*
X1161580Y-661795D01*
Y-652837D01*
G01X1167470Y-665337D02*
Y-652837D01*
X1171345D01*
X1172585Y-653462D01*
X1173360Y-654295D01*
X1173670Y-655962D01*
X1173360Y-657629D01*
X1172430Y-658670D01*
X1171345Y-659295D01*
X1167470D01*
G01X1171345D02*
X1173670Y-665337D01*
G01X1181110Y-652837D02*
X1184830D01*
G01X1182970D02*
Y-665337D01*
G01X1181110D02*
X1184830D01*
G01X1191805D02*
Y-652837D01*
X1198935Y-665337D01*
Y-652837D01*
G01X1208700Y-659087D02*
X1211800D01*
Y-662837D01*
X1210870Y-664087D01*
X1209785Y-664920D01*
X1208235Y-665337D01*
X1206685Y-664920D01*
X1205600Y-664087D01*
X1204670Y-662837D01*
X1204050Y-661379D01*
X1203740Y-659712D01*
Y-658254D01*
X1204050Y-657004D01*
X1204670Y-655545D01*
X1205600Y-654295D01*
X1206530Y-653462D01*
X1207770Y-652837D01*
X1208855D01*
X1210095Y-653254D01*
X1211025Y-654087D01*
G01X1229315Y-663671D02*
X1230555Y-664712D01*
X1231950Y-665337D01*
X1233190D01*
X1234430Y-664712D01*
X1235360Y-663671D01*
X1235825Y-662212D01*
X1235515Y-660754D01*
X1234740Y-659504D01*
X1233345Y-658670D01*
X1231485Y-658254D01*
X1230400Y-657420D01*
X1229935Y-655962D01*
X1230245Y-654504D01*
X1231020Y-653462D01*
X1232105Y-652837D01*
X1233190D01*
X1234275Y-653254D01*
X1235205Y-654295D01*
G01X1244970Y-652837D02*
Y-665337D01*
G01X1241405Y-652837D02*
X1248535D01*
G01X1253960D02*
Y-661795D01*
X1254580Y-663671D01*
X1255820Y-664920D01*
X1257370Y-665337D01*
X1258920Y-664920D01*
X1260160Y-663671D01*
X1260780Y-661795D01*
Y-652837D01*
G01X1271010Y-658670D02*
X1271630Y-658045D01*
X1272095Y-657004D01*
X1272405Y-655545D01*
X1272095Y-654295D01*
X1271475Y-653462D01*
X1270390Y-652837D01*
X1266205D01*
Y-665337D01*
X1271320D01*
X1272405Y-664504D01*
X1273025Y-663254D01*
X1273335Y-661795D01*
X1273025Y-660337D01*
X1272095Y-659087D01*
X1271010Y-658670D01*
X1266205D01*
G01X1291470Y-652837D02*
Y-665337D01*
X1297670D01*
G01X1310070D02*
X1303870D01*
Y-652837D01*
X1310070D01*
G01X1307590Y-658879D02*
X1303870D01*
G01X1315805Y-665337D02*
Y-652837D01*
X1322935Y-665337D01*
Y-652837D01*
G01X1332700Y-659087D02*
X1335800D01*
Y-662837D01*
X1334870Y-664087D01*
X1333785Y-664920D01*
X1332235Y-665337D01*
X1330685Y-664920D01*
X1329600Y-664087D01*
X1328670Y-662837D01*
X1328050Y-661379D01*
X1327740Y-659712D01*
Y-658254D01*
X1328050Y-657004D01*
X1328670Y-655545D01*
X1329600Y-654295D01*
X1330530Y-653462D01*
X1331770Y-652837D01*
X1332855D01*
X1334095Y-653254D01*
X1335025Y-654087D01*
G01X1344170Y-652837D02*
Y-665337D01*
G01X1340605Y-652837D02*
X1347735D01*
G01X1353315Y-665337D02*
Y-652837D01*
G01X1359825D02*
Y-665337D01*
G01Y-659087D02*
X1353315D01*
G01X1055715Y-644921D02*
X1056955Y-645962D01*
X1058350Y-646587D01*
X1059590D01*
X1060830Y-645962D01*
X1061760Y-644921D01*
X1062225Y-643462D01*
X1061915Y-642004D01*
X1061140Y-640754D01*
X1059745Y-639920D01*
X1057885Y-639504D01*
X1056800Y-638670D01*
X1056335Y-637212D01*
X1056645Y-635754D01*
X1057420Y-634712D01*
X1058505Y-634087D01*
X1059590D01*
X1060675Y-634504D01*
X1061605Y-635545D01*
G01X1067960Y-634087D02*
Y-643045D01*
X1068580Y-644921D01*
X1069820Y-646170D01*
X1071370Y-646587D01*
X1072920Y-646170D01*
X1074160Y-644921D01*
X1074780Y-643045D01*
Y-634087D01*
G01X1080670Y-646587D02*
Y-634087D01*
X1084545D01*
X1085785Y-634712D01*
X1086560Y-635545D01*
X1086870Y-637212D01*
X1086560Y-638879D01*
X1085630Y-639920D01*
X1084545Y-640545D01*
X1080670D01*
G01X1084545D02*
X1086870Y-646587D01*
G01X1093225D02*
Y-634087D01*
X1099115D01*
G01X1096945Y-640129D02*
X1093225D01*
G01X1104695Y-646587D02*
X1108570Y-634087D01*
X1112445Y-646587D01*
G01X1111050Y-642212D02*
X1106090D01*
G01X1124380Y-635129D02*
X1123450Y-634504D01*
X1122365Y-634087D01*
X1121125D01*
X1119730Y-634712D01*
X1118645Y-635754D01*
X1117870Y-637004D01*
X1117250Y-639087D01*
X1117095Y-640962D01*
X1117405Y-642837D01*
X1117870Y-644087D01*
X1118800Y-645337D01*
X1119885Y-646170D01*
X1120970Y-646587D01*
X1122055D01*
X1123140Y-646170D01*
X1124070Y-645546D01*
X1124845Y-644712D01*
G01X1136470Y-646587D02*
X1130270D01*
Y-634087D01*
X1136470D01*
G01X1133990Y-640129D02*
X1130270D01*
G01X1158170Y-646587D02*
X1156930Y-646379D01*
X1155845Y-645546D01*
X1154915Y-644295D01*
X1154295Y-642837D01*
X1153985Y-641170D01*
Y-639504D01*
X1154295Y-637837D01*
X1154915Y-636379D01*
X1155845Y-635129D01*
X1156930Y-634295D01*
X1158170Y-634087D01*
X1159410Y-634295D01*
X1160495Y-635129D01*
X1161425Y-636379D01*
X1162045Y-637837D01*
X1162355Y-639504D01*
Y-641170D01*
X1162045Y-642837D01*
X1161425Y-644295D01*
X1160495Y-645546D01*
X1159410Y-646379D01*
X1158170Y-646587D01*
G01X1167625D02*
Y-634087D01*
X1173515D01*
G01X1171345Y-640129D02*
X1167625D01*
G01X1191340Y-646587D02*
Y-634087D01*
X1195370Y-644504D01*
X1199400Y-634087D01*
Y-646587D01*
G01X1204360Y-634087D02*
Y-643045D01*
X1204980Y-644921D01*
X1206220Y-646170D01*
X1207770Y-646587D01*
X1209320Y-646170D01*
X1210560Y-644921D01*
X1211180Y-643045D01*
Y-634087D01*
G01X1216915Y-644921D02*
X1218155Y-645962D01*
X1219550Y-646587D01*
X1220790D01*
X1222030Y-645962D01*
X1222960Y-644921D01*
X1223425Y-643462D01*
X1223115Y-642004D01*
X1222340Y-640754D01*
X1220945Y-639920D01*
X1219085Y-639504D01*
X1218000Y-638670D01*
X1217535Y-637212D01*
X1217845Y-635754D01*
X1218620Y-634712D01*
X1219705Y-634087D01*
X1220790D01*
X1221875Y-634504D01*
X1222805Y-635545D01*
G01X1232570Y-634087D02*
Y-646587D01*
G01X1229005Y-634087D02*
X1236135D01*
G01X1242955Y-642420D02*
X1246985D01*
G01X1253805Y-646587D02*
Y-634087D01*
X1260935Y-646587D01*
Y-634087D01*
G01X1269770Y-646587D02*
X1268530Y-646379D01*
X1267445Y-645546D01*
X1266515Y-644295D01*
X1265895Y-642837D01*
X1265585Y-641170D01*
Y-639504D01*
X1265895Y-637837D01*
X1266515Y-636379D01*
X1267445Y-635129D01*
X1268530Y-634295D01*
X1269770Y-634087D01*
X1271010Y-634295D01*
X1272095Y-635129D01*
X1273025Y-636379D01*
X1273645Y-637837D01*
X1273955Y-639504D01*
Y-641170D01*
X1273645Y-642837D01*
X1273025Y-644295D01*
X1272095Y-645546D01*
X1271010Y-646379D01*
X1269770Y-646587D01*
G01X1282170Y-634087D02*
Y-646587D01*
G01X1278605Y-634087D02*
X1285735D01*
G01X1292555Y-642420D02*
X1296585D01*
G01X1310380Y-635129D02*
X1309450Y-634504D01*
X1308365Y-634087D01*
X1307125D01*
X1305730Y-634712D01*
X1304645Y-635754D01*
X1303870Y-637004D01*
X1303250Y-639087D01*
X1303095Y-640962D01*
X1303405Y-642837D01*
X1303870Y-644087D01*
X1304800Y-645337D01*
X1305885Y-646170D01*
X1306970Y-646587D01*
X1308055D01*
X1309140Y-646170D01*
X1310070Y-645546D01*
X1310845Y-644712D01*
G01X1315960Y-634087D02*
Y-643045D01*
X1316580Y-644921D01*
X1317820Y-646170D01*
X1319370Y-646587D01*
X1320920Y-646170D01*
X1322160Y-644921D01*
X1322780Y-643045D01*
Y-634087D01*
G01X1331770D02*
Y-646587D01*
G01X1328205Y-634087D02*
X1335335D01*
G01X1342155Y-642420D02*
X1346185D01*
G01X1353470Y-634087D02*
Y-646587D01*
X1359670D01*
G01X1365095D02*
X1368970Y-634087D01*
X1372845Y-646587D01*
G01X1371450Y-642212D02*
X1366490D01*
G01X1381370Y-646587D02*
Y-640962D01*
X1378270Y-634087D01*
G01X1384470D02*
X1381370Y-640962D01*
G01X1396870Y-646587D02*
X1390670D01*
Y-634087D01*
X1396870D01*
G01X1394390Y-640129D02*
X1390670D01*
G01X1403070Y-646587D02*
Y-634087D01*
X1406945D01*
X1408185Y-634712D01*
X1408960Y-635545D01*
X1409270Y-637212D01*
X1408960Y-638879D01*
X1408030Y-639920D01*
X1406945Y-640545D01*
X1403070D01*
G01X1406945D02*
X1409270Y-646587D01*
G01X895755Y-623670D02*
X899785D01*
G01X918540Y-627837D02*
Y-615337D01*
X922570Y-625754D01*
X926600Y-615337D01*
Y-627837D01*
G01X931095D02*
X934970Y-615337D01*
X938845Y-627837D01*
G01X937450Y-623462D02*
X932490D01*
G01X944115Y-627837D02*
X950625Y-615337D01*
G01X944115D02*
X950625Y-627837D01*
G01X955120Y-632004D02*
X964420D01*
G01X968760Y-627837D02*
Y-615337D01*
X971860D01*
X973100Y-615962D01*
X974030Y-616795D01*
X974805Y-618045D01*
X975425Y-619504D01*
X975580Y-621587D01*
X975425Y-623670D01*
X974805Y-625129D01*
X974030Y-626379D01*
X973100Y-627212D01*
X971860Y-627837D01*
X968760D01*
G01X987670D02*
X981470D01*
Y-615337D01*
X987670D01*
G01X985190Y-621379D02*
X981470D01*
G01X993870Y-627837D02*
Y-615337D01*
X997590D01*
X998830Y-615962D01*
X999760Y-617420D01*
X1000070Y-619087D01*
X999760Y-620754D01*
X998985Y-622004D01*
X997590Y-622629D01*
X993870D01*
G01X1009370Y-615337D02*
Y-627837D01*
G01X1005805Y-615337D02*
X1012935D01*
G01X1018515Y-627837D02*
Y-615337D01*
G01X1025025D02*
Y-627837D01*
G01Y-621587D02*
X1018515D01*
G01X1034170Y-628254D02*
X1033860Y-628045D01*
Y-627629D01*
X1034170Y-627420D01*
X1034480Y-627629D01*
Y-628045D01*
X1034170Y-628254D01*
G01Y-622629D02*
X1033860Y-622420D01*
Y-622004D01*
X1034170Y-621795D01*
X1034480Y-622004D01*
Y-622420D01*
X1034170Y-622629D01*
G01X1055560Y-627837D02*
Y-615337D01*
X1058660D01*
X1059900Y-615962D01*
X1060830Y-616795D01*
X1061605Y-618045D01*
X1062225Y-619504D01*
X1062380Y-621587D01*
X1062225Y-623670D01*
X1061605Y-625129D01*
X1060830Y-626379D01*
X1059900Y-627212D01*
X1058660Y-627837D01*
X1055560D01*
G01X1074470D02*
X1068270D01*
Y-615337D01*
X1074470D01*
G01X1071990Y-621379D02*
X1068270D01*
G01X1080670Y-627837D02*
Y-615337D01*
X1084390D01*
X1085630Y-615962D01*
X1086560Y-617420D01*
X1086870Y-619087D01*
X1086560Y-620754D01*
X1085785Y-622004D01*
X1084390Y-622629D01*
X1080670D01*
G01X1096170Y-615337D02*
Y-627837D01*
G01X1092605Y-615337D02*
X1099735D01*
G01X1105315Y-627837D02*
Y-615337D01*
G01X1111825D02*
Y-627837D01*
G01Y-621587D02*
X1105315D01*
G01X1130425Y-627837D02*
Y-615337D01*
X1136315D01*
G01X1134145Y-621379D02*
X1130425D01*
G01X1142670Y-627837D02*
Y-615337D01*
X1146545D01*
X1147785Y-615962D01*
X1148560Y-616795D01*
X1148870Y-618462D01*
X1148560Y-620129D01*
X1147630Y-621170D01*
X1146545Y-621795D01*
X1142670D01*
G01X1146545D02*
X1148870Y-627837D01*
G01X1158170D02*
X1156930Y-627629D01*
X1155845Y-626796D01*
X1154915Y-625545D01*
X1154295Y-624087D01*
X1153985Y-622420D01*
Y-620754D01*
X1154295Y-619087D01*
X1154915Y-617629D01*
X1155845Y-616379D01*
X1156930Y-615545D01*
X1158170Y-615337D01*
X1159410Y-615545D01*
X1160495Y-616379D01*
X1161425Y-617629D01*
X1162045Y-619087D01*
X1162355Y-620754D01*
Y-622420D01*
X1162045Y-624087D01*
X1161425Y-625545D01*
X1160495Y-626796D01*
X1159410Y-627629D01*
X1158170Y-627837D01*
G01X1166540D02*
Y-615337D01*
X1170570Y-625754D01*
X1174600Y-615337D01*
Y-627837D01*
G01X1192115Y-626171D02*
X1193355Y-627212D01*
X1194750Y-627837D01*
X1195990D01*
X1197230Y-627212D01*
X1198160Y-626171D01*
X1198625Y-624712D01*
X1198315Y-623254D01*
X1197540Y-622004D01*
X1196145Y-621170D01*
X1194285Y-620754D01*
X1193200Y-619920D01*
X1192735Y-618462D01*
X1193045Y-617004D01*
X1193820Y-615962D01*
X1194905Y-615337D01*
X1195990D01*
X1197075Y-615754D01*
X1198005Y-616795D01*
G01X1207770Y-615337D02*
Y-627837D01*
G01X1204205Y-615337D02*
X1211335D01*
G01X1216295Y-627837D02*
X1220170Y-615337D01*
X1224045Y-627837D01*
G01X1222650Y-623462D02*
X1217690D01*
G01X1229470Y-627837D02*
Y-615337D01*
X1233345D01*
X1234585Y-615962D01*
X1235360Y-616795D01*
X1235670Y-618462D01*
X1235360Y-620129D01*
X1234430Y-621170D01*
X1233345Y-621795D01*
X1229470D01*
G01X1233345D02*
X1235670Y-627837D01*
G01X1244970Y-615337D02*
Y-627837D01*
G01X1241405Y-615337D02*
X1248535D01*
G01X1266670D02*
Y-627837D01*
X1272870D01*
G01X1278295D02*
X1282170Y-615337D01*
X1286045Y-627837D01*
G01X1284650Y-623462D02*
X1279690D01*
G01X1294570Y-627837D02*
Y-622212D01*
X1291470Y-615337D01*
G01X1297670D02*
X1294570Y-622212D01*
G01X1310070Y-627837D02*
X1303870D01*
Y-615337D01*
X1310070D01*
G01X1307590Y-621379D02*
X1303870D01*
G01X1316270Y-627837D02*
Y-615337D01*
X1320145D01*
X1321385Y-615962D01*
X1322160Y-616795D01*
X1322470Y-618462D01*
X1322160Y-620129D01*
X1321230Y-621170D01*
X1320145Y-621795D01*
X1316270D01*
G01X1320145D02*
X1322470Y-627837D01*
G01X1344170Y-615337D02*
Y-627837D01*
G01X1340605Y-615337D02*
X1347735D01*
G01X1356570Y-627837D02*
X1355330Y-627629D01*
X1354245Y-626796D01*
X1353315Y-625545D01*
X1352695Y-624087D01*
X1352385Y-622420D01*
Y-620754D01*
X1352695Y-619087D01*
X1353315Y-617629D01*
X1354245Y-616379D01*
X1355330Y-615545D01*
X1356570Y-615337D01*
X1357810Y-615545D01*
X1358895Y-616379D01*
X1359825Y-617629D01*
X1360445Y-619087D01*
X1360755Y-620754D01*
Y-622420D01*
X1360445Y-624087D01*
X1359825Y-625545D01*
X1358895Y-626796D01*
X1357810Y-627629D01*
X1356570Y-627837D01*
G01X1381370Y-615337D02*
Y-627837D01*
G01X1377805Y-615337D02*
X1384935D01*
G01X1390515Y-627837D02*
Y-615337D01*
G01X1397025D02*
Y-627837D01*
G01Y-621587D02*
X1390515D01*
G01X1409270Y-627837D02*
X1403070D01*
Y-615337D01*
X1409270D01*
G01X1406790Y-621379D02*
X1403070D01*
G01X895755Y-604920D02*
X899785D01*
G01X918540Y-609087D02*
Y-596587D01*
X922570Y-607004D01*
X926600Y-596587D01*
Y-609087D01*
G01X931405D02*
Y-596587D01*
X938535Y-609087D01*
Y-596587D01*
G01X950780Y-597629D02*
X949850Y-597004D01*
X948765Y-596587D01*
X947525D01*
X946130Y-597212D01*
X945045Y-598254D01*
X944270Y-599504D01*
X943650Y-601587D01*
X943495Y-603462D01*
X943805Y-605337D01*
X944270Y-606587D01*
X945200Y-607837D01*
X946285Y-608670D01*
X947370Y-609087D01*
X948455D01*
X949540Y-608670D01*
X950470Y-608046D01*
X951245Y-607212D01*
G01X955120Y-613254D02*
X964420D01*
G01X969070Y-596587D02*
Y-609087D01*
X975270D01*
G01X980695D02*
X984570Y-596587D01*
X988445Y-609087D01*
G01X987050Y-604712D02*
X982090D01*
G01X996970Y-609087D02*
Y-603462D01*
X993870Y-596587D01*
G01X1000070D02*
X996970Y-603462D01*
G01X1012470Y-609087D02*
X1006270D01*
Y-596587D01*
X1012470D01*
G01X1009990Y-602629D02*
X1006270D01*
G01X1018670Y-609087D02*
Y-596587D01*
X1022545D01*
X1023785Y-597212D01*
X1024560Y-598045D01*
X1024870Y-599712D01*
X1024560Y-601379D01*
X1023630Y-602420D01*
X1022545Y-603045D01*
X1018670D01*
G01X1022545D02*
X1024870Y-609087D01*
G01X1034170Y-609504D02*
X1033860Y-609295D01*
Y-608879D01*
X1034170Y-608670D01*
X1034480Y-608879D01*
Y-609295D01*
X1034170Y-609504D01*
G01Y-603879D02*
X1033860Y-603670D01*
Y-603254D01*
X1034170Y-603045D01*
X1034480Y-603254D01*
Y-603670D01*
X1034170Y-603879D01*
G01X1054940Y-609087D02*
Y-596587D01*
X1058970Y-607004D01*
X1063000Y-596587D01*
Y-609087D01*
G01X1067960Y-596587D02*
Y-605545D01*
X1068580Y-607421D01*
X1069820Y-608670D01*
X1071370Y-609087D01*
X1072920Y-608670D01*
X1074160Y-607421D01*
X1074780Y-605545D01*
Y-596587D01*
G01X1080515Y-607421D02*
X1081755Y-608462D01*
X1083150Y-609087D01*
X1084390D01*
X1085630Y-608462D01*
X1086560Y-607421D01*
X1087025Y-605962D01*
X1086715Y-604504D01*
X1085940Y-603254D01*
X1084545Y-602420D01*
X1082685Y-602004D01*
X1081600Y-601170D01*
X1081135Y-599712D01*
X1081445Y-598254D01*
X1082220Y-597212D01*
X1083305Y-596587D01*
X1084390D01*
X1085475Y-597004D01*
X1086405Y-598045D01*
G01X1096170Y-596587D02*
Y-609087D01*
G01X1092605Y-596587D02*
X1099735D01*
G01X1106555Y-604920D02*
X1110585D01*
G01X1117405Y-609087D02*
Y-596587D01*
X1124535Y-609087D01*
Y-596587D01*
G01X1133370Y-609087D02*
X1132130Y-608879D01*
X1131045Y-608046D01*
X1130115Y-606795D01*
X1129495Y-605337D01*
X1129185Y-603670D01*
Y-602004D01*
X1129495Y-600337D01*
X1130115Y-598879D01*
X1131045Y-597629D01*
X1132130Y-596795D01*
X1133370Y-596587D01*
X1134610Y-596795D01*
X1135695Y-597629D01*
X1136625Y-598879D01*
X1137245Y-600337D01*
X1137555Y-602004D01*
Y-603670D01*
X1137245Y-605337D01*
X1136625Y-606795D01*
X1135695Y-608046D01*
X1134610Y-608879D01*
X1133370Y-609087D01*
G01X1145770Y-596587D02*
Y-609087D01*
G01X1142205Y-596587D02*
X1149335D01*
G01X1156155Y-604920D02*
X1160185D01*
G01X1173980Y-597629D02*
X1173050Y-597004D01*
X1171965Y-596587D01*
X1170725D01*
X1169330Y-597212D01*
X1168245Y-598254D01*
X1167470Y-599504D01*
X1166850Y-601587D01*
X1166695Y-603462D01*
X1167005Y-605337D01*
X1167470Y-606587D01*
X1168400Y-607837D01*
X1169485Y-608670D01*
X1170570Y-609087D01*
X1171655D01*
X1172740Y-608670D01*
X1173670Y-608046D01*
X1174445Y-607212D01*
G01X1179560Y-596587D02*
Y-605545D01*
X1180180Y-607421D01*
X1181420Y-608670D01*
X1182970Y-609087D01*
X1184520Y-608670D01*
X1185760Y-607421D01*
X1186380Y-605545D01*
Y-596587D01*
G01X1195370D02*
Y-609087D01*
G01X1191805Y-596587D02*
X1198935D01*
G01X1205755Y-604920D02*
X1209785D01*
G01X1217070Y-596587D02*
Y-609087D01*
X1223270D01*
G01X1228695D02*
X1232570Y-596587D01*
X1236445Y-609087D01*
G01X1235050Y-604712D02*
X1230090D01*
G01X1244970Y-609087D02*
Y-603462D01*
X1241870Y-596587D01*
G01X1248070D02*
X1244970Y-603462D01*
G01X1260470Y-609087D02*
X1254270D01*
Y-596587D01*
X1260470D01*
G01X1257990Y-602629D02*
X1254270D01*
G01X1266670Y-609087D02*
Y-596587D01*
X1270545D01*
X1271785Y-597212D01*
X1272560Y-598045D01*
X1272870Y-599712D01*
X1272560Y-601379D01*
X1271630Y-602420D01*
X1270545Y-603045D01*
X1266670D01*
G01X1270545D02*
X1272870Y-609087D01*
G01X894205Y-590337D02*
Y-577837D01*
X901335Y-590337D01*
Y-577837D01*
G01X910170Y-590337D02*
X908930Y-590129D01*
X907845Y-589296D01*
X906915Y-588045D01*
X906295Y-586587D01*
X905985Y-584920D01*
Y-583254D01*
X906295Y-581587D01*
X906915Y-580129D01*
X907845Y-578879D01*
X908930Y-578045D01*
X910170Y-577837D01*
X911410Y-578045D01*
X912495Y-578879D01*
X913425Y-580129D01*
X914045Y-581587D01*
X914355Y-583254D01*
Y-584920D01*
X914045Y-586587D01*
X913425Y-588045D01*
X912495Y-589296D01*
X911410Y-590129D01*
X910170Y-590337D01*
G01X922570Y-577837D02*
Y-590337D01*
G01X919005Y-577837D02*
X926135D01*
G01X938070Y-590337D02*
X931870D01*
Y-577837D01*
X938070D01*
G01X935590Y-583879D02*
X931870D01*
G01X944115Y-588671D02*
X945355Y-589712D01*
X946750Y-590337D01*
X947990D01*
X949230Y-589712D01*
X950160Y-588671D01*
X950625Y-587212D01*
X950315Y-585754D01*
X949540Y-584504D01*
X948145Y-583670D01*
X946285Y-583254D01*
X945200Y-582420D01*
X944735Y-580962D01*
X945045Y-579504D01*
X945820Y-578462D01*
X946905Y-577837D01*
X947990D01*
X949075Y-578254D01*
X950005Y-579295D01*
G01X959770Y-590754D02*
X959460Y-590545D01*
Y-590129D01*
X959770Y-589920D01*
X960080Y-590129D01*
Y-590545D01*
X959770Y-590754D01*
G01Y-585129D02*
X959460Y-584920D01*
Y-584504D01*
X959770Y-584295D01*
X960080Y-584504D01*
Y-584920D01*
X959770Y-585129D01*
G01X893120Y-552837D02*
Y-452837D01*
X1643320D01*
Y-552837D01*
X893120D01*
G01Y-527837D02*
X1643320D01*
G01X893120Y-502837D02*
X1643320D01*
G01X893120Y-477837D02*
X1643320D01*
G01X904125Y-521587D02*
Y-509087D01*
X910015D01*
G01X907845Y-515129D02*
X904125D01*
G01X917610Y-509087D02*
X921330D01*
G01X919470D02*
Y-521587D01*
G01X917610D02*
X921330D01*
G01X932800Y-515337D02*
X935900D01*
Y-519087D01*
X934970Y-520337D01*
X933885Y-521170D01*
X932335Y-521587D01*
X930785Y-521170D01*
X929700Y-520337D01*
X928770Y-519087D01*
X928150Y-517629D01*
X927840Y-515962D01*
Y-514504D01*
X928150Y-513254D01*
X928770Y-511795D01*
X929700Y-510545D01*
X930630Y-509712D01*
X931870Y-509087D01*
X932955D01*
X934195Y-509504D01*
X935125Y-510337D01*
G01X940860Y-509087D02*
Y-518045D01*
X941480Y-519921D01*
X942720Y-521170D01*
X944270Y-521587D01*
X945820Y-521170D01*
X947060Y-519921D01*
X947680Y-518045D01*
Y-509087D01*
G01X953570Y-521587D02*
Y-509087D01*
X957445D01*
X958685Y-509712D01*
X959460Y-510545D01*
X959770Y-512212D01*
X959460Y-513879D01*
X958530Y-514920D01*
X957445Y-515545D01*
X953570D01*
G01X957445D02*
X959770Y-521587D01*
G01X972170D02*
X965970D01*
Y-509087D01*
X972170D01*
G01X969690Y-515129D02*
X965970D01*
G01X983020Y-502837D02*
Y-552837D01*
G01X1010610Y-514920D02*
X1011230Y-514295D01*
X1011695Y-513254D01*
X1012005Y-511795D01*
X1011695Y-510545D01*
X1011075Y-509712D01*
X1009990Y-509087D01*
X1005805D01*
Y-521587D01*
X1010920D01*
X1012005Y-520754D01*
X1012625Y-519504D01*
X1012935Y-518045D01*
X1012625Y-516587D01*
X1011695Y-515337D01*
X1010610Y-514920D01*
X1005805D01*
G01X1018360Y-521587D02*
Y-509087D01*
X1021460D01*
X1022700Y-509712D01*
X1023630Y-510545D01*
X1024405Y-511795D01*
X1025025Y-513254D01*
X1025180Y-515337D01*
X1025025Y-517420D01*
X1024405Y-518879D01*
X1023630Y-520129D01*
X1022700Y-520962D01*
X1021460Y-521587D01*
X1018360D01*
G01X1029520Y-525754D02*
X1038820D01*
G01X1043315Y-519921D02*
X1044555Y-520962D01*
X1045950Y-521587D01*
X1047190D01*
X1048430Y-520962D01*
X1049360Y-519921D01*
X1049825Y-518462D01*
X1049515Y-517004D01*
X1048740Y-515754D01*
X1047345Y-514920D01*
X1045485Y-514504D01*
X1044400Y-513670D01*
X1043935Y-512212D01*
X1044245Y-510754D01*
X1045020Y-509712D01*
X1046105Y-509087D01*
X1047190D01*
X1048275Y-509504D01*
X1049205Y-510545D01*
G01X1057110Y-509087D02*
X1060830D01*
G01X1058970D02*
Y-521587D01*
G01X1057110D02*
X1060830D01*
G01X1068425Y-509087D02*
X1074315D01*
X1068425Y-521587D01*
X1074315D01*
G01X1086870D02*
X1080670D01*
Y-509087D01*
X1086870D01*
G01X1084390Y-515129D02*
X1080670D01*
G01X1027970Y-546587D02*
Y-534087D01*
X1026110Y-536587D01*
G01Y-546587D02*
X1029830D01*
G01X1037425Y-541379D02*
X1038510Y-539920D01*
X1039440Y-539087D01*
X1040680Y-538670D01*
X1041765Y-539087D01*
X1042540Y-539920D01*
X1043160Y-541170D01*
X1043315Y-542629D01*
X1043160Y-543879D01*
X1042540Y-545129D01*
X1041610Y-546170D01*
X1040525Y-546587D01*
X1039285Y-546170D01*
X1038200Y-544921D01*
X1037580Y-543045D01*
X1037425Y-540962D01*
X1037735Y-538254D01*
X1038200Y-536795D01*
X1038975Y-535337D01*
X1040060Y-534295D01*
X1041145Y-534087D01*
X1042230Y-534504D01*
X1043005Y-535545D01*
G01X1052770Y-547004D02*
X1052460Y-546795D01*
Y-546379D01*
X1052770Y-546170D01*
X1053080Y-546379D01*
Y-546795D01*
X1052770Y-547004D01*
G01X1065170Y-534087D02*
X1063930Y-534504D01*
X1063000Y-535545D01*
X1062380Y-536795D01*
X1061915Y-538462D01*
X1061760Y-540337D01*
X1061915Y-542212D01*
X1062380Y-543879D01*
X1063000Y-545129D01*
X1063930Y-546170D01*
X1065170Y-546587D01*
X1066410Y-546170D01*
X1067340Y-545129D01*
X1067960Y-543879D01*
X1068425Y-542212D01*
X1068580Y-540337D01*
X1068425Y-538462D01*
X1067960Y-536795D01*
X1067340Y-535545D01*
X1066410Y-534504D01*
X1065170Y-534087D01*
G01X1110120Y-502837D02*
Y-552837D01*
G01X1114460Y-464920D02*
X1115080Y-464295D01*
X1115545Y-463254D01*
X1115855Y-461795D01*
X1115545Y-460545D01*
X1114925Y-459712D01*
X1113840Y-459087D01*
X1109655D01*
Y-471587D01*
X1114770D01*
X1115855Y-470754D01*
X1116475Y-469504D01*
X1116785Y-468045D01*
X1116475Y-466587D01*
X1115545Y-465337D01*
X1114460Y-464920D01*
X1109655D01*
G01X1121745Y-471587D02*
X1125620Y-459087D01*
X1129495Y-471587D01*
G01X1128100Y-467212D02*
X1123140D01*
G01X1141430Y-460129D02*
X1140500Y-459504D01*
X1139415Y-459087D01*
X1138175D01*
X1136780Y-459712D01*
X1135695Y-460754D01*
X1134920Y-462004D01*
X1134300Y-464087D01*
X1134145Y-465962D01*
X1134455Y-467837D01*
X1134920Y-469087D01*
X1135850Y-470337D01*
X1136935Y-471170D01*
X1138020Y-471587D01*
X1139105D01*
X1140190Y-471170D01*
X1141120Y-470546D01*
X1141895Y-469712D01*
G01X1147010Y-471587D02*
Y-459087D01*
G01X1152900D02*
X1147010Y-466796D01*
G01X1153830Y-471587D02*
X1149645Y-463254D01*
G01X1159410Y-471587D02*
Y-459087D01*
X1162510D01*
X1163750Y-459712D01*
X1164680Y-460545D01*
X1165455Y-461795D01*
X1166075Y-463254D01*
X1166230Y-465337D01*
X1166075Y-467420D01*
X1165455Y-468879D01*
X1164680Y-470129D01*
X1163750Y-470962D01*
X1162510Y-471587D01*
X1159410D01*
G01X1172120D02*
Y-459087D01*
X1175995D01*
X1177235Y-459712D01*
X1178010Y-460545D01*
X1178320Y-462212D01*
X1178010Y-463879D01*
X1177080Y-464920D01*
X1175995Y-465545D01*
X1172120D01*
G01X1175995D02*
X1178320Y-471587D01*
G01X1185760Y-459087D02*
X1189480D01*
G01X1187620D02*
Y-471587D01*
G01X1185760D02*
X1189480D01*
G01X1196920Y-459087D02*
Y-471587D01*
X1203120D01*
G01X1209320Y-459087D02*
Y-471587D01*
X1215520D01*
G01X1224820Y-472004D02*
X1224510Y-471795D01*
Y-471379D01*
X1224820Y-471170D01*
X1225130Y-471379D01*
Y-471795D01*
X1224820Y-472004D01*
G01Y-466379D02*
X1224510Y-466170D01*
Y-465754D01*
X1224820Y-465545D01*
X1225130Y-465754D01*
Y-466170D01*
X1224820Y-466379D01*
G01X1249620Y-459087D02*
Y-471587D01*
G01X1246055Y-459087D02*
X1253185D01*
G01X1262020Y-471587D02*
X1260780Y-471379D01*
X1259695Y-470546D01*
X1258765Y-469295D01*
X1258145Y-467837D01*
X1257835Y-466170D01*
Y-464504D01*
X1258145Y-462837D01*
X1258765Y-461379D01*
X1259695Y-460129D01*
X1260780Y-459295D01*
X1262020Y-459087D01*
X1263260Y-459295D01*
X1264345Y-460129D01*
X1265275Y-461379D01*
X1265895Y-462837D01*
X1266205Y-464504D01*
Y-466170D01*
X1265895Y-467837D01*
X1265275Y-469295D01*
X1264345Y-470546D01*
X1263260Y-471379D01*
X1262020Y-471587D01*
G01X1271320D02*
Y-459087D01*
X1275040D01*
X1276280Y-459712D01*
X1277210Y-461170D01*
X1277520Y-462837D01*
X1277210Y-464504D01*
X1276435Y-465754D01*
X1275040Y-466379D01*
X1271320D01*
G01X1299220Y-459087D02*
Y-471587D01*
G01X1297050Y-463254D02*
X1301390D01*
G01X1311620Y-471587D02*
X1310690Y-471379D01*
X1309760Y-470546D01*
X1309140Y-469087D01*
X1308830Y-467420D01*
X1309140Y-465754D01*
X1309760Y-464295D01*
X1310690Y-463462D01*
X1311620Y-463254D01*
X1312550Y-463462D01*
X1313480Y-464295D01*
X1314100Y-465754D01*
X1314255Y-467420D01*
X1314100Y-469087D01*
X1313480Y-470546D01*
X1312550Y-471379D01*
X1311620Y-471587D01*
G01X1333320Y-459087D02*
Y-471587D01*
X1339520D01*
G01X1348820Y-459087D02*
X1347580Y-459504D01*
X1346650Y-460545D01*
X1346030Y-461795D01*
X1345565Y-463462D01*
X1345410Y-465337D01*
X1345565Y-467212D01*
X1346030Y-468879D01*
X1346650Y-470129D01*
X1347580Y-471170D01*
X1348820Y-471587D01*
X1350060Y-471170D01*
X1350990Y-470129D01*
X1351610Y-468879D01*
X1352075Y-467212D01*
X1352230Y-465337D01*
X1352075Y-463462D01*
X1351610Y-461795D01*
X1350990Y-460545D01*
X1350060Y-459504D01*
X1348820Y-459087D01*
G01X1360910Y-471587D02*
X1361220Y-468879D01*
X1361685Y-466587D01*
X1362305Y-464504D01*
X1363080Y-462212D01*
X1364320Y-459087D01*
X1358120D01*
G01X1368970Y-475754D02*
X1378270D01*
G01X1386950Y-465337D02*
X1390050D01*
Y-469087D01*
X1389120Y-470337D01*
X1388035Y-471170D01*
X1386485Y-471587D01*
X1384935Y-471170D01*
X1383850Y-470337D01*
X1382920Y-469087D01*
X1382300Y-467629D01*
X1381990Y-465962D01*
Y-464504D01*
X1382300Y-463254D01*
X1382920Y-461795D01*
X1383850Y-460545D01*
X1384780Y-459712D01*
X1386020Y-459087D01*
X1387105D01*
X1388345Y-459504D01*
X1389275Y-460337D01*
G01X1394855Y-471587D02*
Y-459087D01*
X1401985Y-471587D01*
Y-459087D01*
G01X1407410Y-471587D02*
Y-459087D01*
X1410510D01*
X1411750Y-459712D01*
X1412680Y-460545D01*
X1413455Y-461795D01*
X1414075Y-463254D01*
X1414230Y-465337D01*
X1414075Y-467420D01*
X1413455Y-468879D01*
X1412680Y-470129D01*
X1411750Y-470962D01*
X1410510Y-471587D01*
X1407410D01*
G01X1419810Y-469087D02*
X1420740Y-470546D01*
X1421980Y-471379D01*
X1423375Y-471587D01*
X1424615Y-471379D01*
X1425855Y-470337D01*
X1426630Y-469087D01*
X1426785Y-467837D01*
X1426475Y-466379D01*
X1425390Y-465337D01*
X1424305Y-464920D01*
X1422910D01*
G01X1424305D02*
X1425235Y-464295D01*
X1426010Y-463254D01*
X1426320Y-462004D01*
X1426010Y-460754D01*
X1425235Y-459712D01*
X1423840Y-459087D01*
X1422445Y-459295D01*
X1421050Y-460129D01*
G01X1140345Y-496587D02*
X1144220Y-484087D01*
X1148095Y-496587D01*
G01X1146700Y-492212D02*
X1141740D01*
G01X1153520Y-484087D02*
Y-496587D01*
X1159720D01*
G01X1165920Y-484087D02*
Y-496587D01*
X1172120D01*
G01X1190410Y-484087D02*
Y-493045D01*
X1191030Y-494921D01*
X1192270Y-496170D01*
X1193820Y-496587D01*
X1195370Y-496170D01*
X1196610Y-494921D01*
X1197230Y-493045D01*
Y-484087D01*
G01X1202655Y-496587D02*
Y-484087D01*
X1209785Y-496587D01*
Y-484087D01*
G01X1216760D02*
X1220480D01*
G01X1218620D02*
Y-496587D01*
G01X1216760D02*
X1220480D01*
G01X1231020Y-484087D02*
Y-496587D01*
G01X1227455Y-484087D02*
X1234585D01*
G01X1240165Y-494921D02*
X1241405Y-495962D01*
X1242800Y-496587D01*
X1244040D01*
X1245280Y-495962D01*
X1246210Y-494921D01*
X1246675Y-493462D01*
X1246365Y-492004D01*
X1245590Y-490754D01*
X1244195Y-489920D01*
X1242335Y-489504D01*
X1241250Y-488670D01*
X1240785Y-487212D01*
X1241095Y-485754D01*
X1241870Y-484712D01*
X1242955Y-484087D01*
X1244040D01*
X1245125Y-484504D01*
X1246055Y-485545D01*
G01X1264345Y-496587D02*
X1268220Y-484087D01*
X1272095Y-496587D01*
G01X1270700Y-492212D02*
X1265740D01*
G01X1277520Y-496587D02*
Y-484087D01*
X1281395D01*
X1282635Y-484712D01*
X1283410Y-485545D01*
X1283720Y-487212D01*
X1283410Y-488879D01*
X1282480Y-489920D01*
X1281395Y-490545D01*
X1277520D01*
G01X1281395D02*
X1283720Y-496587D01*
G01X1296120D02*
X1289920D01*
Y-484087D01*
X1296120D01*
G01X1293640Y-490129D02*
X1289920D01*
G01X1315960Y-484087D02*
X1319680D01*
G01X1317820D02*
Y-496587D01*
G01X1315960D02*
X1319680D01*
G01X1326655D02*
Y-484087D01*
X1333785Y-496587D01*
Y-484087D01*
G01X1350990Y-496587D02*
Y-484087D01*
X1355020Y-494504D01*
X1359050Y-484087D01*
Y-496587D01*
G01X1365560Y-484087D02*
X1369280D01*
G01X1367420D02*
Y-496587D01*
G01X1365560D02*
X1369280D01*
G01X1376720Y-484087D02*
Y-496587D01*
X1382920D01*
G01X1388965Y-494921D02*
X1390205Y-495962D01*
X1391600Y-496587D01*
X1392840D01*
X1394080Y-495962D01*
X1395010Y-494921D01*
X1395475Y-493462D01*
X1395165Y-492004D01*
X1394390Y-490754D01*
X1392995Y-489920D01*
X1391135Y-489504D01*
X1390050Y-488670D01*
X1389585Y-487212D01*
X1389895Y-485754D01*
X1390670Y-484712D01*
X1391755Y-484087D01*
X1392840D01*
X1393925Y-484504D01*
X1394855Y-485545D01*
G01X1157240Y-521587D02*
Y-509087D01*
X1161270Y-519504D01*
X1165300Y-509087D01*
Y-521587D01*
G01X1170105D02*
Y-509087D01*
X1177235Y-521587D01*
Y-509087D01*
G01X1189480Y-510129D02*
X1188550Y-509504D01*
X1187465Y-509087D01*
X1186225D01*
X1184830Y-509712D01*
X1183745Y-510754D01*
X1182970Y-512004D01*
X1182350Y-514087D01*
X1182195Y-515962D01*
X1182505Y-517837D01*
X1182970Y-519087D01*
X1183900Y-520337D01*
X1184985Y-521170D01*
X1186070Y-521587D01*
X1187155D01*
X1188240Y-521170D01*
X1189170Y-520546D01*
X1189945Y-519712D01*
G01X1193820Y-525754D02*
X1203120D01*
G01X1207770Y-509087D02*
Y-521587D01*
X1213970D01*
G01X1219395D02*
X1223270Y-509087D01*
X1227145Y-521587D01*
G01X1225750Y-517212D02*
X1220790D01*
G01X1235670Y-521587D02*
Y-515962D01*
X1232570Y-509087D01*
G01X1238770D02*
X1235670Y-515962D01*
G01X1251170Y-521587D02*
X1244970D01*
Y-509087D01*
X1251170D01*
G01X1248690Y-515129D02*
X1244970D01*
G01X1257370Y-521587D02*
Y-509087D01*
X1261245D01*
X1262485Y-509712D01*
X1263260Y-510545D01*
X1263570Y-512212D01*
X1263260Y-513879D01*
X1262330Y-514920D01*
X1261245Y-515545D01*
X1257370D01*
G01X1261245D02*
X1263570Y-521587D01*
G01X1164370Y-534087D02*
Y-546587D01*
X1170570D01*
G01X1179870Y-534087D02*
X1178630Y-534504D01*
X1177700Y-535545D01*
X1177080Y-536795D01*
X1176615Y-538462D01*
X1176460Y-540337D01*
X1176615Y-542212D01*
X1177080Y-543879D01*
X1177700Y-545129D01*
X1178630Y-546170D01*
X1179870Y-546587D01*
X1181110Y-546170D01*
X1182040Y-545129D01*
X1182660Y-543879D01*
X1183125Y-542212D01*
X1183280Y-540337D01*
X1183125Y-538462D01*
X1182660Y-536795D01*
X1182040Y-535545D01*
X1181110Y-534504D01*
X1179870Y-534087D01*
G01X1192270Y-546587D02*
X1193355Y-546379D01*
X1194595Y-545754D01*
X1195370Y-544712D01*
X1195680Y-543254D01*
X1195370Y-541796D01*
X1194440Y-540545D01*
X1193045Y-539920D01*
X1191495D01*
X1190565Y-539504D01*
X1189790Y-538462D01*
X1189480Y-537004D01*
X1189945Y-535545D01*
X1191030Y-534504D01*
X1192270Y-534087D01*
X1193510Y-534504D01*
X1194595Y-535545D01*
X1195060Y-537004D01*
X1194750Y-538462D01*
X1193975Y-539504D01*
X1193045Y-539920D01*
X1191495D01*
X1190100Y-540545D01*
X1189170Y-541796D01*
X1188860Y-543254D01*
X1189170Y-544712D01*
X1189945Y-545754D01*
X1191185Y-546379D01*
X1192270Y-546587D01*
G01X1200020Y-550754D02*
X1209320D01*
G01X1213815Y-544921D02*
X1215055Y-545962D01*
X1216450Y-546587D01*
X1217690D01*
X1218930Y-545962D01*
X1219860Y-544921D01*
X1220325Y-543462D01*
X1220015Y-542004D01*
X1219240Y-540754D01*
X1217845Y-539920D01*
X1215985Y-539504D01*
X1214900Y-538670D01*
X1214435Y-537212D01*
X1214745Y-535754D01*
X1215520Y-534712D01*
X1216605Y-534087D01*
X1217690D01*
X1218775Y-534504D01*
X1219705Y-535545D01*
G01X1227610Y-534087D02*
X1231330D01*
G01X1229470D02*
Y-546587D01*
G01X1227610D02*
X1231330D01*
G01X1242800Y-540337D02*
X1245900D01*
Y-544087D01*
X1244970Y-545337D01*
X1243885Y-546170D01*
X1242335Y-546587D01*
X1240785Y-546170D01*
X1239700Y-545337D01*
X1238770Y-544087D01*
X1238150Y-542629D01*
X1237840Y-540962D01*
Y-539504D01*
X1238150Y-538254D01*
X1238770Y-536795D01*
X1239700Y-535545D01*
X1240630Y-534712D01*
X1241870Y-534087D01*
X1242955D01*
X1244195Y-534504D01*
X1245125Y-535337D01*
G01X1251325Y-536170D02*
X1252255Y-534921D01*
X1253340Y-534295D01*
X1254580Y-534087D01*
X1256130Y-534504D01*
X1257215Y-535545D01*
X1257525Y-536795D01*
X1257370Y-538046D01*
X1256750Y-539087D01*
X1253650Y-541170D01*
X1252255Y-542629D01*
X1251325Y-544712D01*
X1251015Y-546587D01*
X1257525D01*
G01X1311620Y-502837D02*
Y-552837D01*
G01X1321540Y-521587D02*
Y-509087D01*
X1325570Y-519504D01*
X1329600Y-509087D01*
Y-521587D01*
G01X1334095D02*
X1337970Y-509087D01*
X1341845Y-521587D01*
G01X1340450Y-517212D02*
X1335490D01*
G01X1347115Y-521587D02*
X1353625Y-509087D01*
G01X1347115D02*
X1353625Y-521587D01*
G01X1358120Y-525754D02*
X1367420D01*
G01X1371760Y-521587D02*
Y-509087D01*
X1374860D01*
X1376100Y-509712D01*
X1377030Y-510545D01*
X1377805Y-511795D01*
X1378425Y-513254D01*
X1378580Y-515337D01*
X1378425Y-517420D01*
X1377805Y-518879D01*
X1377030Y-520129D01*
X1376100Y-520962D01*
X1374860Y-521587D01*
X1371760D01*
G01X1390670D02*
X1384470D01*
Y-509087D01*
X1390670D01*
G01X1388190Y-515129D02*
X1384470D01*
G01X1396870Y-521587D02*
Y-509087D01*
X1400590D01*
X1401830Y-509712D01*
X1402760Y-511170D01*
X1403070Y-512837D01*
X1402760Y-514504D01*
X1401985Y-515754D01*
X1400590Y-516379D01*
X1396870D01*
G01X1412370Y-509087D02*
Y-521587D01*
G01X1408805Y-509087D02*
X1415935D01*
G01X1421515Y-521587D02*
Y-509087D01*
G01X1428025D02*
Y-521587D01*
G01Y-515337D02*
X1421515D01*
G01X1358430Y-546587D02*
Y-534087D01*
X1352695Y-543045D01*
X1360445D01*
G01X1366335Y-545129D02*
X1367420Y-546170D01*
X1368660Y-546587D01*
X1369900Y-546170D01*
X1370985Y-544921D01*
X1371760Y-543045D01*
X1372070Y-541170D01*
Y-538879D01*
X1371760Y-537004D01*
X1370985Y-535337D01*
X1370055Y-534504D01*
X1368970Y-534087D01*
X1367730Y-534504D01*
X1366800Y-535337D01*
X1366180Y-536587D01*
X1365870Y-538254D01*
X1366180Y-539712D01*
X1366955Y-541170D01*
X1367885Y-542004D01*
X1368970Y-542212D01*
X1370210Y-541796D01*
X1371140Y-540754D01*
X1372070Y-538879D01*
G01X1381370Y-547004D02*
X1381060Y-546795D01*
Y-546379D01*
X1381370Y-546170D01*
X1381680Y-546379D01*
Y-546795D01*
X1381370Y-547004D01*
G01X1393770Y-546587D02*
X1394855Y-546379D01*
X1396095Y-545754D01*
X1396870Y-544712D01*
X1397180Y-543254D01*
X1396870Y-541796D01*
X1395940Y-540545D01*
X1394545Y-539920D01*
X1392995D01*
X1392065Y-539504D01*
X1391290Y-538462D01*
X1390980Y-537004D01*
X1391445Y-535545D01*
X1392530Y-534504D01*
X1393770Y-534087D01*
X1395010Y-534504D01*
X1396095Y-535545D01*
X1396560Y-537004D01*
X1396250Y-538462D01*
X1395475Y-539504D01*
X1394545Y-539920D01*
X1392995D01*
X1391600Y-540545D01*
X1390670Y-541796D01*
X1390360Y-543254D01*
X1390670Y-544712D01*
X1391445Y-545754D01*
X1392685Y-546379D01*
X1393770Y-546587D01*
G01X1390570Y-559087D02*
Y-571587D01*
G01X1387005Y-559087D02*
X1394135D01*
G01X1402970Y-571587D02*
X1401730Y-571379D01*
X1400645Y-570546D01*
X1399715Y-569295D01*
X1399095Y-567837D01*
X1398785Y-566170D01*
Y-564504D01*
X1399095Y-562837D01*
X1399715Y-561379D01*
X1400645Y-560129D01*
X1401730Y-559295D01*
X1402970Y-559087D01*
X1404210Y-559295D01*
X1405295Y-560129D01*
X1406225Y-561379D01*
X1406845Y-562837D01*
X1407155Y-564504D01*
Y-566170D01*
X1406845Y-567837D01*
X1406225Y-569295D01*
X1405295Y-570546D01*
X1404210Y-571379D01*
X1402970Y-571587D01*
G01X1415370Y-559087D02*
Y-571587D01*
G01X1411805Y-559087D02*
X1418935D01*
G01X1423895Y-571587D02*
X1427770Y-559087D01*
X1431645Y-571587D01*
G01X1430250Y-567212D02*
X1425290D01*
G01X1437070Y-559087D02*
Y-571587D01*
X1443270D01*
G01X1466210Y-564920D02*
X1466830Y-564295D01*
X1467295Y-563254D01*
X1467605Y-561795D01*
X1467295Y-560545D01*
X1466675Y-559712D01*
X1465590Y-559087D01*
X1461405D01*
Y-571587D01*
X1466520D01*
X1467605Y-570754D01*
X1468225Y-569504D01*
X1468535Y-568045D01*
X1468225Y-566587D01*
X1467295Y-565337D01*
X1466210Y-564920D01*
X1461405D01*
G01X1473495Y-571587D02*
X1477370Y-559087D01*
X1481245Y-571587D01*
G01X1479850Y-567212D02*
X1474890D01*
G01X1493180Y-560129D02*
X1492250Y-559504D01*
X1491165Y-559087D01*
X1489925D01*
X1488530Y-559712D01*
X1487445Y-560754D01*
X1486670Y-562004D01*
X1486050Y-564087D01*
X1485895Y-565962D01*
X1486205Y-567837D01*
X1486670Y-569087D01*
X1487600Y-570337D01*
X1488685Y-571170D01*
X1489770Y-571587D01*
X1490855D01*
X1491940Y-571170D01*
X1492870Y-570546D01*
X1493645Y-569712D01*
G01X1498760Y-571587D02*
Y-559087D01*
G01X1504650D02*
X1498760Y-566796D01*
G01X1505580Y-571587D02*
X1501395Y-563254D01*
G01X1511160Y-571587D02*
Y-559087D01*
X1514260D01*
X1515500Y-559712D01*
X1516430Y-560545D01*
X1517205Y-561795D01*
X1517825Y-563254D01*
X1517980Y-565337D01*
X1517825Y-567420D01*
X1517205Y-568879D01*
X1516430Y-570129D01*
X1515500Y-570962D01*
X1514260Y-571587D01*
X1511160D01*
G01X1523870D02*
Y-559087D01*
X1527745D01*
X1528985Y-559712D01*
X1529760Y-560545D01*
X1530070Y-562212D01*
X1529760Y-563879D01*
X1528830Y-564920D01*
X1527745Y-565545D01*
X1523870D01*
G01X1527745D02*
X1530070Y-571587D01*
G01X1537510Y-559087D02*
X1541230D01*
G01X1539370D02*
Y-571587D01*
G01X1537510D02*
X1541230D01*
G01X1548670Y-559087D02*
Y-571587D01*
X1554870D01*
G01X1561070Y-559087D02*
Y-571587D01*
X1567270D01*
G01X1573315Y-569921D02*
X1574555Y-570962D01*
X1575950Y-571587D01*
X1577190D01*
X1578430Y-570962D01*
X1579360Y-569921D01*
X1579825Y-568462D01*
X1579515Y-567004D01*
X1578740Y-565754D01*
X1577345Y-564920D01*
X1575485Y-564504D01*
X1574400Y-563670D01*
X1573935Y-562212D01*
X1574245Y-560754D01*
X1575020Y-559712D01*
X1576105Y-559087D01*
X1577190D01*
X1578275Y-559504D01*
X1579205Y-560545D01*
G01X1588970Y-572004D02*
X1588660Y-571795D01*
Y-571379D01*
X1588970Y-571170D01*
X1589280Y-571379D01*
Y-571795D01*
X1588970Y-572004D01*
G01Y-566379D02*
X1588660Y-566170D01*
Y-565754D01*
X1588970Y-565545D01*
X1589280Y-565754D01*
Y-566170D01*
X1588970Y-566379D01*
G01X1613770Y-571587D02*
Y-559087D01*
X1611910Y-561587D01*
G01Y-571587D02*
X1615630D01*
G01X1626170Y-559087D02*
X1624930Y-559504D01*
X1624000Y-560545D01*
X1623380Y-561795D01*
X1622915Y-563462D01*
X1622760Y-565337D01*
X1622915Y-567212D01*
X1623380Y-568879D01*
X1624000Y-570129D01*
X1624930Y-571170D01*
X1626170Y-571587D01*
X1627410Y-571170D01*
X1628340Y-570129D01*
X1628960Y-568879D01*
X1629425Y-567212D01*
X1629580Y-565337D01*
X1629425Y-563462D01*
X1628960Y-561795D01*
X1628340Y-560545D01*
X1627410Y-559504D01*
X1626170Y-559087D01*
G01X1438720Y-502837D02*
Y-552837D01*
G01X1454840Y-521587D02*
Y-509087D01*
X1458870Y-519504D01*
X1462900Y-509087D01*
Y-521587D01*
G01X1468325D02*
Y-509087D01*
X1474215D01*
G01X1472045Y-515129D02*
X1468325D01*
G01X1484600Y-515337D02*
X1487700D01*
Y-519087D01*
X1486770Y-520337D01*
X1485685Y-521170D01*
X1484135Y-521587D01*
X1482585Y-521170D01*
X1481500Y-520337D01*
X1480570Y-519087D01*
X1479950Y-517629D01*
X1479640Y-515962D01*
Y-514504D01*
X1479950Y-513254D01*
X1480570Y-511795D01*
X1481500Y-510545D01*
X1482430Y-509712D01*
X1483670Y-509087D01*
X1484755D01*
X1485995Y-509504D01*
X1486925Y-510337D01*
G01X1491420Y-525754D02*
X1500720D01*
G01X1505215Y-519921D02*
X1506455Y-520962D01*
X1507850Y-521587D01*
X1509090D01*
X1510330Y-520962D01*
X1511260Y-519921D01*
X1511725Y-518462D01*
X1511415Y-517004D01*
X1510640Y-515754D01*
X1509245Y-514920D01*
X1507385Y-514504D01*
X1506300Y-513670D01*
X1505835Y-512212D01*
X1506145Y-510754D01*
X1506920Y-509712D01*
X1508005Y-509087D01*
X1509090D01*
X1510175Y-509504D01*
X1511105Y-510545D01*
G01X1520870Y-509087D02*
Y-521587D01*
G01X1517305Y-509087D02*
X1524435D01*
G01X1529860D02*
Y-518045D01*
X1530480Y-519921D01*
X1531720Y-521170D01*
X1533270Y-521587D01*
X1534820Y-521170D01*
X1536060Y-519921D01*
X1536680Y-518045D01*
Y-509087D01*
G01X1546910Y-514920D02*
X1547530Y-514295D01*
X1547995Y-513254D01*
X1548305Y-511795D01*
X1547995Y-510545D01*
X1547375Y-509712D01*
X1546290Y-509087D01*
X1542105D01*
Y-521587D01*
X1547220D01*
X1548305Y-520754D01*
X1548925Y-519504D01*
X1549235Y-518045D01*
X1548925Y-516587D01*
X1547995Y-515337D01*
X1546910Y-514920D01*
X1542105D01*
G01X1500255Y-542420D02*
X1504285D01*
G01X1565820Y-502837D02*
Y-552837D01*
G01X1598370Y-546587D02*
Y-534087D01*
X1596510Y-536587D01*
G01Y-546587D02*
X1600230D01*
G01X1610770Y-534087D02*
X1609530Y-534504D01*
X1608600Y-535545D01*
X1607980Y-536795D01*
X1607515Y-538462D01*
X1607360Y-540337D01*
X1607515Y-542212D01*
X1607980Y-543879D01*
X1608600Y-545129D01*
X1609530Y-546170D01*
X1610770Y-546587D01*
X1612010Y-546170D01*
X1612940Y-545129D01*
X1613560Y-543879D01*
X1614025Y-542212D01*
X1614180Y-540337D01*
X1614025Y-538462D01*
X1613560Y-536795D01*
X1612940Y-535545D01*
X1612010Y-534504D01*
X1610770Y-534087D01*
G01X1592170Y-521587D02*
X1590930Y-521379D01*
X1589845Y-520546D01*
X1588915Y-519295D01*
X1588295Y-517837D01*
X1587985Y-516170D01*
Y-514504D01*
X1588295Y-512837D01*
X1588915Y-511379D01*
X1589845Y-510129D01*
X1590930Y-509295D01*
X1592170Y-509087D01*
X1593410Y-509295D01*
X1594495Y-510129D01*
X1595425Y-511379D01*
X1596045Y-512837D01*
X1596355Y-514504D01*
Y-516170D01*
X1596045Y-517837D01*
X1595425Y-519295D01*
X1594495Y-520546D01*
X1593410Y-521379D01*
X1592170Y-521587D01*
G01X1593410Y-518254D02*
X1595270Y-521587D01*
G01X1604570Y-509087D02*
Y-521587D01*
G01X1601005Y-509087D02*
X1608135D01*
G01X1616970Y-521587D02*
Y-515962D01*
X1613870Y-509087D01*
G01X1620070D02*
X1616970Y-515962D01*
M02*
